FILE_TYPE = CONNECTIVITY;
{Allegro Design Entry HDL 16.6-p007 (v16-6-112F) 10/10/2012}
"PAGE_NUMBER" = 57;
0"NC";
1"M_G_DQS_DP<17:0>";
2"M_G_DQS_DN<17:0>";
3"M_G_MA<17:0>";
4"M_G_BA<1:0>";
5"M_G_BG<1:0>";
6"M_G_CKE<3:0>";
7"M_G_CS_N<7:0>";
8"M_G_ODT<3:0>";
9"M_G_DQ<63:0>";
10"M_G_CLK_DN<3:0>";
11"M_G_CLK_DP<3:0>";
12"M_G_ECC<7:0>";
13"M_G_DQ<55>";
14"M_G_ECC<1>";
15"M_G_DQ<41>";
16"M_G_DQ<28>";
17"M_G_DQ<52>";
18"M_G_ODT<2>";
19"M_G_DQ<34>";
20"M_G_DQ<3>";
21"M_G_DQ<32>";
22"M_G_C<2>";
23"M_G_ECC<0>";
24"M_G_ECC<2>";
25"M_G_ECC<3>";
26"M_G_ECC<4>";
27"M_G_ECC<5>";
28"M_G_ECC<6>";
29"M_G_ECC<7>";
30"M_G_DQ<0>";
31"M_G_DQ<1>";
32"M_G_DQ<2>";
33"M_G_DQ<4>";
34"M_G_DQ<5>";
35"M_G_DQ<6>";
36"M_G_DQ<7>";
37"M_G_DQ<8>";
38"M_G_DQ<9>";
39"M_G_DQ<10>";
40"M_G_CLK_DP<0>";
41"M_G_CLK_DP<1>";
42"M_G_CLK_DP<2>";
43"M_G_CLK_DP<3>";
44"M_G_CLK_DN<0>";
45"M_G_CLK_DN<1>";
46"M_G_CLK_DN<2>";
47"M_G_CLK_DN<3>";
48"M_G_DQ<11>";
49"M_G_DQ<12>";
50"M_G_DQ<13>";
51"M_G_DQ<14>";
52"M_G_DQ<15>";
53"M_G_DQ<16>";
54"M_G_DQ<17>";
55"M_G_DQ<18>";
56"M_G_DQ<19>";
57"M_G_DQ<20>";
58"M_G_DQ<21>";
59"M_G_DQ<22>";
60"M_G_DQ<23>";
61"M_G_DQ<24>";
62"M_G_DQ<25>";
63"M_G_DQ<26>";
64"M_G_DQ<27>";
65"M_G_DQ<29>";
66"M_G_DQ<30>";
67"M_G_DQ<31>";
68"M_G_DQ<33>";
69"M_G_DQ<35>";
70"M_G_DQ<36>";
71"M_G_DQ<37>";
72"M_G_DQ<38>";
73"M_G_DQ<39>";
74"M_G_DQ<40>";
75"M_G_DQ<42>";
76"M_G_DQ<43>";
77"M_G_DQ<44>";
78"M_G_DQ<45>";
79"M_G_DQ<46>";
80"M_G_DQ<47>";
81"M_G_DQ<48>";
82"M_G_DQ<49>";
83"M_G_DQ<50>";
84"M_G_DQ<51>";
85"M_G_DQ<53>";
86"M_G_DQ<54>";
87"M_G_DQ<56>";
88"M_G_DQ<57>";
89"M_G_DQ<58>";
90"M_G_DQ<59>";
91"M_G_DQ<60>";
92"M_G_DQ<61>";
93"M_G_DQ<62>";
94"M_G_DQ<63>";
95"M_G_ODT<0>";
96"M_G_ODT<1>";
97"M_G_ODT<3>";
98"M_G_MA<0>";
99"M_G_MA<1>";
100"M_G_MA<2>";
101"M_G_CS_N<0>";
102"M_G_CS_N<1>";
103"M_G_CS_N<2>";
104"M_G_CS_N<3>";
105"M_G_CS_N<4>";
106"M_G_CS_N<5>";
107"M_G_CS_N<6>";
108"M_G_CS_N<7>";
109"M_G_CKE<0>";
110"M_G_CKE<1>";
111"M_G_CKE<2>";
112"M_G_CKE<3>";
113"M_G_BG<0>";
114"M_G_BG<1>";
115"M_G_BA<0>";
116"M_G_BA<1>";
117"M_G_PAR";
118"M_G_ALERT_N";
119"M_G_ACT_N";
120"M_G_MA<3>";
121"M_G_MA<4>";
122"M_G_MA<5>";
123"M_G_MA<6>";
124"M_G_MA<7>";
125"M_G_MA<8>";
126"M_G_MA<9>";
127"M_G_MA<10>";
128"M_G_MA<11>";
129"M_G_MA<12>";
130"M_G_MA<13>";
131"M_G_MA<14>";
132"M_G_MA<15>";
133"M_G_MA<16>";
134"M_G_MA<17>";
135"M_G_DQS_DP<0>";
136"M_G_DQS_DP<1>";
137"M_G_DQS_DP<2>";
138"M_G_DQS_DP<3>";
139"M_G_DQS_DP<4>";
140"M_G_DQS_DP<5>";
141"M_G_DQS_DN<0>";
142"M_G_DQS_DN<1>";
143"M_G_DQS_DN<2>";
144"M_G_DQS_DN<3>";
145"M_G_DQS_DN<4>";
146"M_G_DQS_DN<5>";
147"M_G_DQS_DN<6>";
148"M_G_DQS_DN<7>";
149"M_G_DQS_DN<8>";
150"M_G_DQS_DN<9>";
151"M_G_DQS_DN<10>";
152"M_G_DQS_DN<11>";
153"M_G_DQS_DN<12>";
154"M_G_DQS_DN<13>";
155"M_G_DQS_DN<14>";
156"M_G_DQS_DN<15>";
157"M_G_DQS_DN<16>";
158"M_G_DQS_DN<17>";
159"M_G_DQS_DP<6>";
160"M_G_DQS_DP<7>";
161"M_G_DQS_DP<8>";
162"M_G_DQS_DP<9>";
163"M_G_DQS_DP<10>";
164"M_G_DQS_DP<11>";
165"M_G_DQS_DP<12>";
166"M_G_DQS_DP<13>";
167"M_G_DQS_DP<14>";
168"M_G_DQS_DP<15>";
169"M_G_DQS_DP<16>";
170"M_G_DQS_DP<17>";
%"TAP"
"6","(-5575,825)","0","mstr_standard","I10";
;
CDS_LIB"mstr_standard"
BODY_TYPE"PLUMBING"
HDL_TAP"TRUE";
"B \NAC \NWC"11;
"S \NAC"
BN"0"40;
%"TAP"
"6","(-2850,1575)","2","mstr_standard","I100";
;
CDS_LIB"mstr_standard"
BODY_TYPE"PLUMBING"
HDL_TAP"TRUE";
"B \NAC \NWC"8;
"S \NAC"
BN"3"97;
%"TAP"
"6","(-2850,1525)","2","mstr_standard","I101";
;
CDS_LIB"mstr_standard"
BODY_TYPE"PLUMBING"
HDL_TAP"TRUE";
"B \NAC \NWC"8;
"S \NAC"
BN"2"18;
%"TAP"
"6","(-2850,1475)","2","mstr_standard","I102";
;
CDS_LIB"mstr_standard"
BODY_TYPE"PLUMBING"
HDL_TAP"TRUE";
"B \NAC \NWC"8;
"S \NAC"
BN"1"96;
%"TAP"
"6","(-2850,1675)","2","mstr_standard","I103";
;
CDS_LIB"mstr_standard"
BODY_TYPE"PLUMBING"
HDL_TAP"TRUE";
"B \NAC \NWC"6;
"S \NAC"
BN"0"109;
%"TAP"
"6","(-2850,1725)","2","mstr_standard","I104";
;
CDS_LIB"mstr_standard"
BODY_TYPE"PLUMBING"
HDL_TAP"TRUE";
"B \NAC \NWC"6;
"S \NAC"
BN"1"110;
%"TAP"
"6","(-2850,1775)","2","mstr_standard","I105";
;
CDS_LIB"mstr_standard"
BODY_TYPE"PLUMBING"
HDL_TAP"TRUE";
"B \NAC \NWC"6;
"S \NAC"
BN"2"111;
%"TAP"
"6","(-2850,1825)","2","mstr_standard","I106";
;
CDS_LIB"mstr_standard"
BODY_TYPE"PLUMBING"
HDL_TAP"TRUE";
"B \NAC \NWC"6;
"S \NAC"
BN"3"112;
%"TAP"
"6","(-2850,1925)","2","mstr_standard","I107";
;
CDS_LIB"mstr_standard"
BODY_TYPE"PLUMBING"
HDL_TAP"TRUE";
"B \NAC \NWC"3;
"S \NAC"
BN"0"98;
%"TAP"
"6","(-2850,1975)","2","mstr_standard","I108";
;
CDS_LIB"mstr_standard"
BODY_TYPE"PLUMBING"
HDL_TAP"TRUE";
"B \NAC \NWC"3;
"S \NAC"
BN"1"99;
%"TAP"
"6","(-2850,2075)","2","mstr_standard","I109";
;
CDS_LIB"mstr_standard"
BODY_TYPE"PLUMBING"
HDL_TAP"TRUE";
"B \NAC \NWC"3;
"S \NAC"
BN"3"120;
%"TAP"
"6","(-5575,925)","0","mstr_standard","I11";
;
CDS_LIB"mstr_standard"
BODY_TYPE"PLUMBING"
HDL_TAP"TRUE";
"B \NAC \NWC"11;
"S \NAC"
BN"2"42;
%"TAP"
"6","(-2850,2025)","2","mstr_standard","I110";
;
CDS_LIB"mstr_standard"
BODY_TYPE"PLUMBING"
HDL_TAP"TRUE";
"B \NAC \NWC"3;
"S \NAC"
BN"2"100;
%"TAP"
"6","(-2850,2125)","2","mstr_standard","I111";
;
CDS_LIB"mstr_standard"
BODY_TYPE"PLUMBING"
HDL_TAP"TRUE";
"B \NAC \NWC"3;
"S \NAC"
BN"4"121;
%"TAP"
"6","(-2850,2175)","2","mstr_standard","I112";
;
CDS_LIB"mstr_standard"
BODY_TYPE"PLUMBING"
HDL_TAP"TRUE";
"B \NAC \NWC"3;
"S \NAC"
BN"5"122;
%"TAP"
"6","(-2850,2225)","2","mstr_standard","I113";
;
CDS_LIB"mstr_standard"
BODY_TYPE"PLUMBING"
HDL_TAP"TRUE";
"B \NAC \NWC"3;
"S \NAC"
BN"6"123;
%"TAP"
"6","(-2850,2325)","2","mstr_standard","I114";
;
CDS_LIB"mstr_standard"
BODY_TYPE"PLUMBING"
HDL_TAP"TRUE";
"B \NAC \NWC"3;
"S \NAC"
BN"8"125;
%"TAP"
"6","(-2850,2275)","2","mstr_standard","I115";
;
CDS_LIB"mstr_standard"
BODY_TYPE"PLUMBING"
HDL_TAP"TRUE";
"B \NAC \NWC"3;
"S \NAC"
BN"7"124;
%"TAP"
"6","(-2850,2475)","2","mstr_standard","I116";
;
CDS_LIB"mstr_standard"
BODY_TYPE"PLUMBING"
HDL_TAP"TRUE";
"B \NAC \NWC"3;
"S \NAC"
BN"11"128;
%"TAP"
"6","(-2850,2425)","2","mstr_standard","I117";
;
CDS_LIB"mstr_standard"
BODY_TYPE"PLUMBING"
HDL_TAP"TRUE";
"B \NAC \NWC"3;
"S \NAC"
BN"10"127;
%"TAP"
"6","(-2850,2375)","2","mstr_standard","I118";
;
CDS_LIB"mstr_standard"
BODY_TYPE"PLUMBING"
HDL_TAP"TRUE";
"B \NAC \NWC"3;
"S \NAC"
BN"9"126;
%"TAP"
"6","(-2850,2525)","2","mstr_standard","I119";
;
CDS_LIB"mstr_standard"
BODY_TYPE"PLUMBING"
HDL_TAP"TRUE";
"B \NAC \NWC"3;
"S \NAC"
BN"12"129;
%"TAP"
"6","(-5575,975)","0","mstr_standard","I12";
;
CDS_LIB"mstr_standard"
BODY_TYPE"PLUMBING"
HDL_TAP"TRUE";
"B \NAC \NWC"11;
"S \NAC"
BN"3"43;
%"TAP"
"6","(-2850,2575)","2","mstr_standard","I120";
;
CDS_LIB"mstr_standard"
BODY_TYPE"PLUMBING"
HDL_TAP"TRUE";
"B \NAC \NWC"3;
"S \NAC"
BN"13"130;
%"TAP"
"6","(-2850,2625)","2","mstr_standard","I121";
;
CDS_LIB"mstr_standard"
BODY_TYPE"PLUMBING"
HDL_TAP"TRUE";
"B \NAC \NWC"3;
"S \NAC"
BN"14"131;
%"TAP"
"6","(-2850,2675)","2","mstr_standard","I122";
;
CDS_LIB"mstr_standard"
BODY_TYPE"PLUMBING"
HDL_TAP"TRUE";
"B \NAC \NWC"3;
"S \NAC"
BN"15"132;
%"TAP"
"6","(-2850,2725)","2","mstr_standard","I123";
;
CDS_LIB"mstr_standard"
BODY_TYPE"PLUMBING"
HDL_TAP"TRUE";
"B \NAC \NWC"3;
"S \NAC"
BN"16"133;
%"TAP"
"6","(-2850,2775)","2","mstr_standard","I124";
;
CDS_LIB"mstr_standard"
BODY_TYPE"PLUMBING"
HDL_TAP"TRUE";
"B \NAC \NWC"3;
"S \NAC"
BN"17"134;
%"TAP"
"6","(-2850,2925)","2","mstr_standard","I125";
;
CDS_LIB"mstr_standard"
BODY_TYPE"PLUMBING"
HDL_TAP"TRUE";
"B \NAC \NWC"2;
"S \NAC"
BN"1"142;
%"TAP"
"6","(-2850,2975)","2","mstr_standard","I126";
;
CDS_LIB"mstr_standard"
BODY_TYPE"PLUMBING"
HDL_TAP"TRUE";
"B \NAC \NWC"2;
"S \NAC"
BN"2"143;
%"TAP"
"6","(-2850,2875)","2","mstr_standard","I127";
;
CDS_LIB"mstr_standard"
BODY_TYPE"PLUMBING"
HDL_TAP"TRUE";
"B \NAC \NWC"2;
"S \NAC"
BN"0"141;
%"TAP"
"6","(-2850,3075)","2","mstr_standard","I128";
;
CDS_LIB"mstr_standard"
BODY_TYPE"PLUMBING"
HDL_TAP"TRUE";
"B \NAC \NWC"2;
"S \NAC"
BN"4"145;
%"TAP"
"6","(-2850,3025)","2","mstr_standard","I129";
;
CDS_LIB"mstr_standard"
BODY_TYPE"PLUMBING"
HDL_TAP"TRUE";
"B \NAC \NWC"2;
"S \NAC"
BN"3"144;
%"TAP"
"6","(-5575,1075)","0","mstr_standard","I13";
;
CDS_LIB"mstr_standard"
BODY_TYPE"PLUMBING"
HDL_TAP"TRUE";
"B \NAC \NWC"12;
"S \NAC"
BN"0"23;
%"TAP"
"6","(-2850,3125)","2","mstr_standard","I130";
;
CDS_LIB"mstr_standard"
BODY_TYPE"PLUMBING"
HDL_TAP"TRUE";
"B \NAC \NWC"2;
"S \NAC"
BN"5"146;
%"TAP"
"6","(-2850,3175)","2","mstr_standard","I131";
;
CDS_LIB"mstr_standard"
BODY_TYPE"PLUMBING"
HDL_TAP"TRUE";
"B \NAC \NWC"2;
"S \NAC"
BN"6"147;
%"TAP"
"6","(-2850,3225)","2","mstr_standard","I132";
;
CDS_LIB"mstr_standard"
BODY_TYPE"PLUMBING"
HDL_TAP"TRUE";
"B \NAC \NWC"2;
"S \NAC"
BN"7"148;
%"TAP"
"6","(-2850,3275)","2","mstr_standard","I133";
;
CDS_LIB"mstr_standard"
BODY_TYPE"PLUMBING"
HDL_TAP"TRUE";
"B \NAC \NWC"2;
"S \NAC"
BN"8"149;
%"TAP"
"6","(-2850,3325)","2","mstr_standard","I134";
;
CDS_LIB"mstr_standard"
BODY_TYPE"PLUMBING"
HDL_TAP"TRUE";
"B \NAC \NWC"2;
"S \NAC"
BN"9"150;
%"TAP"
"6","(-2850,3375)","2","mstr_standard","I135";
;
CDS_LIB"mstr_standard"
BODY_TYPE"PLUMBING"
HDL_TAP"TRUE";
"B \NAC \NWC"2;
"S \NAC"
BN"10"151;
%"TAP"
"6","(-2850,3475)","2","mstr_standard","I136";
;
CDS_LIB"mstr_standard"
BODY_TYPE"PLUMBING"
HDL_TAP"TRUE";
"B \NAC \NWC"2;
"S \NAC"
BN"12"153;
%"TAP"
"6","(-2850,3425)","2","mstr_standard","I137";
;
CDS_LIB"mstr_standard"
BODY_TYPE"PLUMBING"
HDL_TAP"TRUE";
"B \NAC \NWC"2;
"S \NAC"
BN"11"152;
%"TAP"
"6","(-2850,3625)","2","mstr_standard","I138";
;
CDS_LIB"mstr_standard"
BODY_TYPE"PLUMBING"
HDL_TAP"TRUE";
"B \NAC \NWC"2;
"S \NAC"
BN"15"156;
%"TAP"
"6","(-2850,3575)","2","mstr_standard","I139";
;
CDS_LIB"mstr_standard"
BODY_TYPE"PLUMBING"
HDL_TAP"TRUE";
"B \NAC \NWC"2;
"S \NAC"
BN"14"155;
%"TAP"
"6","(-5575,1125)","0","mstr_standard","I14";
;
CDS_LIB"mstr_standard"
BODY_TYPE"PLUMBING"
HDL_TAP"TRUE";
"B \NAC \NWC"12;
"S \NAC"
BN"1"14;
%"TAP"
"6","(-2850,3525)","2","mstr_standard","I140";
;
CDS_LIB"mstr_standard"
BODY_TYPE"PLUMBING"
HDL_TAP"TRUE";
"B \NAC \NWC"2;
"S \NAC"
BN"13"154;
%"TAP"
"6","(-2850,3675)","2","mstr_standard","I141";
;
CDS_LIB"mstr_standard"
BODY_TYPE"PLUMBING"
HDL_TAP"TRUE";
"B \NAC \NWC"2;
"S \NAC"
BN"16"157;
%"TAP"
"6","(-2850,3725)","2","mstr_standard","I142";
;
CDS_LIB"mstr_standard"
BODY_TYPE"PLUMBING"
HDL_TAP"TRUE";
"B \NAC \NWC"2;
"S \NAC"
BN"17"158;
%"TAP"
"6","(-2850,3825)","2","mstr_standard","I143";
;
CDS_LIB"mstr_standard"
BODY_TYPE"PLUMBING"
HDL_TAP"TRUE";
"B \NAC \NWC"1;
"S \NAC"
BN"0"135;
%"TAP"
"6","(-2850,3875)","2","mstr_standard","I144";
;
CDS_LIB"mstr_standard"
BODY_TYPE"PLUMBING"
HDL_TAP"TRUE";
"B \NAC \NWC"1;
"S \NAC"
BN"1"136;
%"TAP"
"6","(-2850,3925)","2","mstr_standard","I145";
;
CDS_LIB"mstr_standard"
BODY_TYPE"PLUMBING"
HDL_TAP"TRUE";
"B \NAC \NWC"1;
"S \NAC"
BN"2"137;
%"TAP"
"6","(-2850,3975)","2","mstr_standard","I146";
;
CDS_LIB"mstr_standard"
BODY_TYPE"PLUMBING"
HDL_TAP"TRUE";
"B \NAC \NWC"1;
"S \NAC"
BN"3"138;
%"TAP"
"6","(-5575,1175)","0","mstr_standard","I15";
;
CDS_LIB"mstr_standard"
BODY_TYPE"PLUMBING"
HDL_TAP"TRUE";
"B \NAC \NWC"12;
"S \NAC"
BN"2"24;
%"TAP"
"6","(-2850,4025)","2","mstr_standard","I157";
;
CDS_LIB"mstr_standard"
BODY_TYPE"PLUMBING"
HDL_TAP"TRUE";
"B \NAC \NWC"1;
"S \NAC"
BN"4"139;
%"TAP"
"6","(-2850,4125)","2","mstr_standard","I158";
;
CDS_LIB"mstr_standard"
BODY_TYPE"PLUMBING"
HDL_TAP"TRUE";
"B \NAC \NWC"1;
"S \NAC"
BN"6"159;
%"TAP"
"6","(-2850,4075)","2","mstr_standard","I159";
;
CDS_LIB"mstr_standard"
BODY_TYPE"PLUMBING"
HDL_TAP"TRUE";
"B \NAC \NWC"1;
"S \NAC"
BN"5"140;
%"TAP"
"6","(-5575,1275)","0","mstr_standard","I16";
;
CDS_LIB"mstr_standard"
BODY_TYPE"PLUMBING"
HDL_TAP"TRUE";
"B \NAC \NWC"12;
"S \NAC"
BN"4"26;
%"TAP"
"6","(-2850,4175)","2","mstr_standard","I160";
;
CDS_LIB"mstr_standard"
BODY_TYPE"PLUMBING"
HDL_TAP"TRUE";
"B \NAC \NWC"1;
"S \NAC"
BN"7"160;
%"TAP"
"6","(-2850,4225)","2","mstr_standard","I161";
;
CDS_LIB"mstr_standard"
BODY_TYPE"PLUMBING"
HDL_TAP"TRUE";
"B \NAC \NWC"1;
"S \NAC"
BN"8"161;
%"TAP"
"6","(-2850,4275)","2","mstr_standard","I162";
;
CDS_LIB"mstr_standard"
BODY_TYPE"PLUMBING"
HDL_TAP"TRUE";
"B \NAC \NWC"1;
"S \NAC"
BN"9"162;
%"TAP"
"6","(-2850,4325)","2","mstr_standard","I163";
;
CDS_LIB"mstr_standard"
BODY_TYPE"PLUMBING"
HDL_TAP"TRUE";
"B \NAC \NWC"1;
"S \NAC"
BN"10"163;
%"TAP"
"6","(-2850,4375)","2","mstr_standard","I164";
;
CDS_LIB"mstr_standard"
BODY_TYPE"PLUMBING"
HDL_TAP"TRUE";
"B \NAC \NWC"1;
"S \NAC"
BN"11"164;
%"TAP"
"6","(-2850,4525)","2","mstr_standard","I165";
;
CDS_LIB"mstr_standard"
BODY_TYPE"PLUMBING"
HDL_TAP"TRUE";
"B \NAC \NWC"1;
"S \NAC"
BN"14"167;
%"TAP"
"6","(-2850,4475)","2","mstr_standard","I166";
;
CDS_LIB"mstr_standard"
BODY_TYPE"PLUMBING"
HDL_TAP"TRUE";
"B \NAC \NWC"1;
"S \NAC"
BN"13"166;
%"TAP"
"6","(-2850,4425)","2","mstr_standard","I167";
;
CDS_LIB"mstr_standard"
BODY_TYPE"PLUMBING"
HDL_TAP"TRUE";
"B \NAC \NWC"1;
"S \NAC"
BN"12"165;
%"TAP"
"6","(-2850,4575)","2","mstr_standard","I168";
;
CDS_LIB"mstr_standard"
BODY_TYPE"PLUMBING"
HDL_TAP"TRUE";
"B \NAC \NWC"1;
"S \NAC"
BN"15"168;
%"TAP"
"6","(-2850,4625)","2","mstr_standard","I169";
;
CDS_LIB"mstr_standard"
BODY_TYPE"PLUMBING"
HDL_TAP"TRUE";
"B \NAC \NWC"1;
"S \NAC"
BN"16"169;
%"TAP"
"6","(-5575,1225)","0","mstr_standard","I17";
;
CDS_LIB"mstr_standard"
BODY_TYPE"PLUMBING"
HDL_TAP"TRUE";
"B \NAC \NWC"12;
"S \NAC"
BN"3"25;
%"TAP"
"6","(-2850,4675)","2","mstr_standard","I170";
;
CDS_LIB"mstr_standard"
BODY_TYPE"PLUMBING"
HDL_TAP"TRUE";
"B \NAC \NWC"1;
"S \NAC"
BN"17"170;
%"SKX_EXT_B"
"3","(-4175,2575)","0","chpset_lib","I172";
;
CDS_SEC"3"
LOCATION"U2D1"
PART_NUMBER"TBD"
MATERIAL"IC"
PACK_TYPE"BGA1"
SEC_TYPE"BGA1"
CDS_LIB"chpset_lib"
SEC"3"
CDS_LOCATION"U2D1";
"DDR0_PAR"
$PN"D53"117;
"DDR0_ODT<0>"
$PN"C50"95;
"DDR0_ODT<1>"
$PN"C48"96;
"DDR0_ODT<2>"
$PN"G50"18;
"DDR0_ODT<3>"
$PN"G48"97;
"DDR0_MA<0>"
$PN"F53"98;
"DDR0_MA<1>"
$PN"F57"99;
"DDR0_MA<2>"
$PN"D57"100;
"DDR0_MA<3>"
$PN"C58"120;
"DDR0_MA<4>"
$PN"G58"121;
"DDR0_MA<5>"
$PN"F59"122;
"DDR0_MA<6>"
$PN"D59"123;
"DDR0_MA<7>"
$PN"G60"124;
"DDR0_MA<8>"
$PN"C60"125;
"DDR0_MA<9>"
$PN"F61"126;
"DDR0_MA<10>"
$PN"J54"127;
"DDR0_MA<11>"
$PN"G62"128;
"DDR0_MA<12>"
$PN"J64"129;
"DDR0_MA<13>"
$PN"J48"130;
"DDR0_MA<14>"
$PN"F51"131;
"DDR0_MA<15>"
$PN"K49"132;
"DDR0_MA<16>"
$PN"D51"133;
"DDR0_MA<17>"
$PN"K47"134;
"DDR0_ECC<0>"
$PN"AC68"23;
"DDR0_ECC<1>"
$PN"AG68"14;
"DDR0_ECC<2>"
$PN"AD65"24;
"DDR0_ECC<3>"
$PN"AF65"25;
"DDR0_ECC<4>"
$PN"AD69"26;
"DDR0_ECC<5>"
$PN"AF69"27;
"DDR0_ECC<6>"
$PN"AC66"28;
"DDR0_ECC<7>"
$PN"AG66"29;
"DDR0_DQS_DP<0>"
$PN"AH85"135;
"DDR0_DQS_DP<1>"
$PN"P85"136;
"DDR0_DQS_DP<2>"
$PN"R80"137;
"DDR0_DQS_DP<3>"
$PN"P75"138;
"DDR0_DQS_DP<4>"
$PN"E40"139;
"DDR0_DQS_DP<5>"
$PN"N36"140;
"DDR0_DQS_DP<6>"
$PN"N30"159;
"DDR0_DQS_DP<7>"
$PN"R24"160;
"DDR0_DQS_DP<8>"
$PN"AF67"161;
"DDR0_DQS_DP<9>"
$PN"AM85"162;
"DDR0_DQS_DP<10>"
$PN"V85"163;
"DDR0_DQS_DP<11>"
$PN"T81"164;
"DDR0_DQS_DP<12>"
$PN"M75"165;
"DDR0_DQS_DP<13>"
$PN"C40"166;
"DDR0_DQS_DP<14>"
$PN"L36"167;
"DDR0_DQS_DP<15>"
$PN"L30"168;
"DDR0_DQS_DP<16>"
$PN"L24"169;
"DDR0_DQS_DP<17>"
$PN"AD67"170;
"DDR0_DQS_DN<0>"
$PN"AJ84"141;
"DDR0_DQS_DN<1>"
$PN"R84"142;
"DDR0_DQS_DN<2>"
$PN"P79"143;
"DDR0_DQS_DN<3>"
$PN"T75"144;
"DDR0_DQS_DN<4>"
$PN"G40"145;
"DDR0_DQS_DN<5>"
$PN"R36"146;
"DDR0_DQS_DN<6>"
$PN"R30"147;
"DDR0_DQS_DN<7>"
$PN"N24"148;
"DDR0_DQS_DN<8>"
$PN"AH67"149;
"DDR0_DQS_DN<9>"
$PN"AL84"150;
"DDR0_DQS_DN<10>"
$PN"U84"151;
"DDR0_DQS_DN<11>"
$PN"U82"152;
"DDR0_DQS_DN<12>"
$PN"K75"153;
"DDR0_DQS_DN<13>"
$PN"A40"154;
"DDR0_DQS_DN<14>"
$PN"J36"155;
"DDR0_DQS_DN<15>"
$PN"J30"156;
"DDR0_DQS_DN<16>"
$PN"J24"157;
"DDR0_DQS_DN<17>"
$PN"AB67"158;
"DDR0_DQ<0>"
$PN"AN86"30;
"DDR0_DQ<1>"
$PN"AN84"31;
"DDR0_DQ<2>"
$PN"AE86"32;
"DDR0_DQ<3>"
$PN"AE84"20;
"DDR0_DQ<4>"
$PN"AR86"33;
"DDR0_DQ<5>"
$PN"AR84"34;
"DDR0_DQ<6>"
$PN"AG86"35;
"DDR0_DQ<7>"
$PN"AG84"36;
"DDR0_DQ<8>"
$PN"W86"37;
"DDR0_DQ<9>"
$PN"W84"38;
"DDR0_DQ<10>"
$PN"L86"39;
"DDR0_DQ<11>"
$PN"L84"48;
"DDR0_DQ<12>"
$PN"AA86"49;
"DDR0_DQ<13>"
$PN"AA84"50;
"DDR0_DQ<14>"
$PN"N86"51;
"DDR0_DQ<15>"
$PN"N84"52;
"DDR0_DQ<16>"
$PN"V81"53;
"DDR0_DQ<17>"
$PN"T79"54;
"DDR0_DQ<18>"
$PN"N82"55;
"DDR0_DQ<19>"
$PN"M81"56;
"DDR0_DQ<20>"
$PN"W80"57;
"DDR0_DQ<21>"
$PN"V79"58;
"DDR0_DQ<22>"
$PN"R82"59;
"DDR0_DQ<23>"
$PN"N80"60;
"DDR0_DQ<24>"
$PN"L76"61;
"DDR0_DQ<25>"
$PN"R76"62;
"DDR0_DQ<26>"
$PN"M73"63;
"DDR0_DQ<27>"
$PN"P73"64;
"DDR0_DQ<28>"
$PN"M77"16;
"DDR0_DQ<29>"
$PN"P77"65;
"DDR0_DQ<30>"
$PN"L74"66;
"DDR0_DQ<31>"
$PN"R74"67;
"DDR0_DQ<32>"
$PN"C42"21;
"DDR0_DQ<33>"
$PN"B41"68;
"DDR0_DQ<34>"
$PN"C38"19;
"DDR0_DQ<35>"
$PN"E38"69;
"DDR0_DQ<36>"
$PN"E42"70;
"DDR0_DQ<37>"
$PN"F41"71;
"DDR0_DQ<38>"
$PN"B39"72;
"DDR0_DQ<39>"
$PN"F39"73;
"DDR0_DQ<40>"
$PN"K37"74;
"DDR0_DQ<41>"
$PN"P37"15;
"DDR0_DQ<42>"
$PN"L34"75;
"DDR0_DQ<43>"
$PN"N34"76;
"DDR0_DQ<44>"
$PN"L38"77;
"DDR0_DQ<45>"
$PN"N38"78;
"DDR0_DQ<46>"
$PN"K35"79;
"DDR0_DQ<47>"
$PN"P35"80;
"DDR0_DQ<48>"
$PN"K31"81;
"DDR0_DQ<49>"
$PN"P31"82;
"DDR0_DQ<50>"
$PN"L28"83;
"DDR0_DQ<51>"
$PN"N28"84;
"DDR0_DQ<52>"
$PN"L32"17;
"DDR0_DQ<53>"
$PN"N32"85;
"DDR0_DQ<54>"
$PN"K29"86;
"DDR0_DQ<55>"
$PN"P29"13;
"DDR0_DQ<56>"
$PN"K25"87;
"DDR0_DQ<57>"
$PN"P25"88;
"DDR0_DQ<58>"
$PN"P23"89;
"DDR0_DQ<59>"
$PN"T23"90;
"DDR0_DQ<60>"
$PN"L26"91;
"DDR0_DQ<61>"
$PN"N26"92;
"DDR0_DQ<62>"
$PN"H23"93;
"DDR0_DQ<63>"
$PN"K23"94;
"DDR0_CS_N<0>"
$PN"G52"101;
"DDR0_CS_N<1>"
$PN"F49"102;
"DDR0_CS_N<2>"
$PN"D47"103;
"DDR0_CS_N<3>"
$PN"F47"104;
"DDR0_CS_N<4>"
$PN"B51"105;
"DDR0_CS_N<5>"
$PN"D49"106;
"DDR0_CS_N<6>"
$PN"F45"107;
"DDR0_CS_N<7>"
$PN"K45"108;
"DDR0_CLK_DP<0>"
$PN"D55"40;
"DDR0_CLK_DP<1>"
$PN"B55"41;
"DDR0_CLK_DP<2>"
$PN"G56"42;
"DDR0_CLK_DP<3>"
$PN"B57"43;
"DDR0_CLK_DN<0>"
$PN"F55"44;
"DDR0_CLK_DN<1>"
$PN"C54"45;
"DDR0_CLK_DN<2>"
$PN"J56"46;
"DDR0_CLK_DN<3>"
$PN"C56"47;
"DDR0_CKE<0>"
$PN"C62"109;
"DDR0_CKE<1>"
$PN"C64"110;
"DDR0_CKE<2>"
$PN"B63"111;
"DDR0_CKE<3>"
$PN"D63"112;
"DDR0_CID<2>"
$PN"G46"22;
"DDR0_BG<0>"
$PN"D61"113;
"DDR0_BG<1>"
$PN"F63"114;
"DDR0_BA<0>"
$PN"C52"115;
"DDR0_BA<1>"
$PN"G54"116;
"DDR0_ALERT_N"
$PN"B61"118;
"DDR0_ACT_N"
$PN"J60"119;
%"TAP"
"6","(-5575,1325)","0","mstr_standard","I18";
;
CDS_LIB"mstr_standard"
BODY_TYPE"PLUMBING"
HDL_TAP"TRUE";
"B \NAC \NWC"12;
"S \NAC"
BN"5"27;
%"TAP"
"6","(-5575,1375)","0","mstr_standard","I19";
;
CDS_LIB"mstr_standard"
BODY_TYPE"PLUMBING"
HDL_TAP"TRUE";
"B \NAC \NWC"12;
"S \NAC"
BN"6"28;
%"TAP"
"6","(-5575,1425)","0","mstr_standard","I20";
;
CDS_LIB"mstr_standard"
BODY_TYPE"PLUMBING"
HDL_TAP"TRUE";
"B \NAC \NWC"12;
"S \NAC"
BN"7"29;
%"TAP"
"6","(-5575,1525)","0","mstr_standard","I21";
;
CDS_LIB"mstr_standard"
BODY_TYPE"PLUMBING"
HDL_TAP"TRUE";
"B \NAC \NWC"9;
"S \NAC"
BN"0"30;
%"TAP"
"6","(-5575,1575)","0","mstr_standard","I22";
;
CDS_LIB"mstr_standard"
BODY_TYPE"PLUMBING"
HDL_TAP"TRUE";
"B \NAC \NWC"9;
"S \NAC"
BN"1"31;
%"TAP"
"6","(-5575,1625)","0","mstr_standard","I23";
;
CDS_LIB"mstr_standard"
BODY_TYPE"PLUMBING"
HDL_TAP"TRUE";
"B \NAC \NWC"9;
"S \NAC"
BN"2"32;
%"TAP"
"6","(-5575,1675)","0","mstr_standard","I24";
;
CDS_LIB"mstr_standard"
BODY_TYPE"PLUMBING"
HDL_TAP"TRUE";
"B \NAC \NWC"9;
"S \NAC"
BN"3"20;
%"TAP"
"6","(-5575,1725)","0","mstr_standard","I25";
;
CDS_LIB"mstr_standard"
BODY_TYPE"PLUMBING"
HDL_TAP"TRUE";
"B \NAC \NWC"9;
"S \NAC"
BN"4"33;
%"TAP"
"6","(-5575,1775)","0","mstr_standard","I26";
;
CDS_LIB"mstr_standard"
BODY_TYPE"PLUMBING"
HDL_TAP"TRUE";
"B \NAC \NWC"9;
"S \NAC"
BN"5"34;
%"TAP"
"6","(-5575,1825)","0","mstr_standard","I27";
;
CDS_LIB"mstr_standard"
BODY_TYPE"PLUMBING"
HDL_TAP"TRUE";
"B \NAC \NWC"9;
"S \NAC"
BN"6"35;
%"TAP"
"6","(-5575,1925)","0","mstr_standard","I28";
;
CDS_LIB"mstr_standard"
BODY_TYPE"PLUMBING"
HDL_TAP"TRUE";
"B \NAC \NWC"9;
"S \NAC"
BN"8"37;
%"TAP"
"6","(-5575,1875)","0","mstr_standard","I29";
;
CDS_LIB"mstr_standard"
BODY_TYPE"PLUMBING"
HDL_TAP"TRUE";
"B \NAC \NWC"9;
"S \NAC"
BN"7"36;
%"TAP"
"6","(-5575,1975)","0","mstr_standard","I31";
;
CDS_LIB"mstr_standard"
BODY_TYPE"PLUMBING"
HDL_TAP"TRUE";
"B \NAC \NWC"9;
"S \NAC"
BN"9"38;
%"TAP"
"6","(-5575,2025)","0","mstr_standard","I32";
;
CDS_LIB"mstr_standard"
BODY_TYPE"PLUMBING"
HDL_TAP"TRUE";
"B \NAC \NWC"9;
"S \NAC"
BN"10"39;
%"TAP"
"6","(-5575,2075)","0","mstr_standard","I33";
;
CDS_LIB"mstr_standard"
BODY_TYPE"PLUMBING"
HDL_TAP"TRUE";
"B \NAC \NWC"9;
"S \NAC"
BN"11"48;
%"TAP"
"6","(-5575,2125)","0","mstr_standard","I34";
;
CDS_LIB"mstr_standard"
BODY_TYPE"PLUMBING"
HDL_TAP"TRUE";
"B \NAC \NWC"9;
"S \NAC"
BN"12"49;
%"TAP"
"6","(-5575,2175)","0","mstr_standard","I35";
;
CDS_LIB"mstr_standard"
BODY_TYPE"PLUMBING"
HDL_TAP"TRUE";
"B \NAC \NWC"9;
"S \NAC"
BN"13"50;
%"TAP"
"6","(-5575,2225)","0","mstr_standard","I36";
;
CDS_LIB"mstr_standard"
BODY_TYPE"PLUMBING"
HDL_TAP"TRUE";
"B \NAC \NWC"9;
"S \NAC"
BN"14"51;
%"TAP"
"6","(-5575,2275)","0","mstr_standard","I37";
;
CDS_LIB"mstr_standard"
BODY_TYPE"PLUMBING"
HDL_TAP"TRUE";
"B \NAC \NWC"9;
"S \NAC"
BN"15"52;
%"TAP"
"6","(-5575,2325)","0","mstr_standard","I38";
;
CDS_LIB"mstr_standard"
BODY_TYPE"PLUMBING"
HDL_TAP"TRUE";
"B \NAC \NWC"9;
"S \NAC"
BN"16"53;
%"TAP"
"6","(-5575,2375)","0","mstr_standard","I39";
;
CDS_LIB"mstr_standard"
BODY_TYPE"PLUMBING"
HDL_TAP"TRUE";
"B \NAC \NWC"9;
"S \NAC"
BN"17"54;
%"TAP"
"6","(-5575,2425)","0","mstr_standard","I40";
;
CDS_LIB"mstr_standard"
BODY_TYPE"PLUMBING"
HDL_TAP"TRUE";
"B \NAC \NWC"9;
"S \NAC"
BN"18"55;
%"TAP"
"6","(-5575,2475)","0","mstr_standard","I41";
;
CDS_LIB"mstr_standard"
BODY_TYPE"PLUMBING"
HDL_TAP"TRUE";
"B \NAC \NWC"9;
"S \NAC"
BN"19"56;
%"TAP"
"6","(-5575,2525)","0","mstr_standard","I42";
;
CDS_LIB"mstr_standard"
BODY_TYPE"PLUMBING"
HDL_TAP"TRUE";
"B \NAC \NWC"9;
"S \NAC"
BN"20"57;
%"TAP"
"6","(-5575,2575)","0","mstr_standard","I43";
;
CDS_LIB"mstr_standard"
BODY_TYPE"PLUMBING"
HDL_TAP"TRUE";
"B \NAC \NWC"9;
"S \NAC"
BN"21"58;
%"TAP"
"6","(-5575,2625)","0","mstr_standard","I44";
;
CDS_LIB"mstr_standard"
BODY_TYPE"PLUMBING"
HDL_TAP"TRUE";
"B \NAC \NWC"9;
"S \NAC"
BN"22"59;
%"TAP"
"6","(-5575,2675)","0","mstr_standard","I45";
;
CDS_LIB"mstr_standard"
BODY_TYPE"PLUMBING"
HDL_TAP"TRUE";
"B \NAC \NWC"9;
"S \NAC"
BN"23"60;
%"TAP"
"6","(-5575,2725)","0","mstr_standard","I46";
;
CDS_LIB"mstr_standard"
BODY_TYPE"PLUMBING"
HDL_TAP"TRUE";
"B \NAC \NWC"9;
"S \NAC"
BN"24"61;
%"TAP"
"6","(-5575,2825)","0","mstr_standard","I47";
;
CDS_LIB"mstr_standard"
BODY_TYPE"PLUMBING"
HDL_TAP"TRUE";
"B \NAC \NWC"9;
"S \NAC"
BN"26"63;
%"TAP"
"6","(-5575,2775)","0","mstr_standard","I48";
;
CDS_LIB"mstr_standard"
BODY_TYPE"PLUMBING"
HDL_TAP"TRUE";
"B \NAC \NWC"9;
"S \NAC"
BN"25"62;
%"TAP"
"6","(-5575,2875)","0","mstr_standard","I49";
;
CDS_LIB"mstr_standard"
BODY_TYPE"PLUMBING"
HDL_TAP"TRUE";
"B \NAC \NWC"9;
"S \NAC"
BN"27"64;
%"TAP"
"6","(-5575,625)","0","mstr_standard","I5";
;
CDS_LIB"mstr_standard"
BODY_TYPE"PLUMBING"
HDL_TAP"TRUE";
"B \NAC \NWC"10;
"S \NAC"
BN"0"44;
%"TAP"
"6","(-5575,2925)","0","mstr_standard","I50";
;
CDS_LIB"mstr_standard"
BODY_TYPE"PLUMBING"
HDL_TAP"TRUE";
"B \NAC \NWC"9;
"S \NAC"
BN"28"16;
%"TAP"
"6","(-5575,2975)","0","mstr_standard","I51";
;
CDS_LIB"mstr_standard"
BODY_TYPE"PLUMBING"
HDL_TAP"TRUE";
"B \NAC \NWC"9;
"S \NAC"
BN"29"65;
%"TAP"
"6","(-5575,3075)","0","mstr_standard","I52";
;
CDS_LIB"mstr_standard"
BODY_TYPE"PLUMBING"
HDL_TAP"TRUE";
"B \NAC \NWC"9;
"S \NAC"
BN"31"67;
%"TAP"
"6","(-5575,3025)","0","mstr_standard","I53";
;
CDS_LIB"mstr_standard"
BODY_TYPE"PLUMBING"
HDL_TAP"TRUE";
"B \NAC \NWC"9;
"S \NAC"
BN"30"66;
%"TAP"
"6","(-5575,3125)","0","mstr_standard","I54";
;
CDS_LIB"mstr_standard"
BODY_TYPE"PLUMBING"
HDL_TAP"TRUE";
"B \NAC \NWC"9;
"S \NAC"
BN"32"21;
%"TAP"
"6","(-5575,3175)","0","mstr_standard","I55";
;
CDS_LIB"mstr_standard"
BODY_TYPE"PLUMBING"
HDL_TAP"TRUE";
"B \NAC \NWC"9;
"S \NAC"
BN"33"68;
%"TAP"
"6","(-5575,3225)","0","mstr_standard","I56";
;
CDS_LIB"mstr_standard"
BODY_TYPE"PLUMBING"
HDL_TAP"TRUE";
"B \NAC \NWC"9;
"S \NAC"
BN"34"19;
%"TAP"
"6","(-5575,3325)","0","mstr_standard","I57";
;
CDS_LIB"mstr_standard"
BODY_TYPE"PLUMBING"
HDL_TAP"TRUE";
"B \NAC \NWC"9;
"S \NAC"
BN"36"70;
%"TAP"
"6","(-5575,3275)","0","mstr_standard","I58";
;
CDS_LIB"mstr_standard"
BODY_TYPE"PLUMBING"
HDL_TAP"TRUE";
"B \NAC \NWC"9;
"S \NAC"
BN"35"69;
%"TAP"
"6","(-5575,3375)","0","mstr_standard","I59";
;
CDS_LIB"mstr_standard"
BODY_TYPE"PLUMBING"
HDL_TAP"TRUE";
"B \NAC \NWC"9;
"S \NAC"
BN"37"71;
%"TAP"
"6","(-5575,675)","0","mstr_standard","I6";
;
CDS_LIB"mstr_standard"
BODY_TYPE"PLUMBING"
HDL_TAP"TRUE";
"B \NAC \NWC"10;
"S \NAC"
BN"1"45;
%"TAP"
"6","(-5575,3425)","0","mstr_standard","I60";
;
CDS_LIB"mstr_standard"
BODY_TYPE"PLUMBING"
HDL_TAP"TRUE";
"B \NAC \NWC"9;
"S \NAC"
BN"38"72;
%"TAP"
"6","(-5575,3475)","0","mstr_standard","I61";
;
CDS_LIB"mstr_standard"
BODY_TYPE"PLUMBING"
HDL_TAP"TRUE";
"B \NAC \NWC"9;
"S \NAC"
BN"39"73;
%"TAP"
"6","(-5575,3525)","0","mstr_standard","I62";
;
CDS_LIB"mstr_standard"
BODY_TYPE"PLUMBING"
HDL_TAP"TRUE";
"B \NAC \NWC"9;
"S \NAC"
BN"40"74;
%"TAP"
"6","(-5575,3575)","0","mstr_standard","I63";
;
CDS_LIB"mstr_standard"
BODY_TYPE"PLUMBING"
HDL_TAP"TRUE";
"B \NAC \NWC"9;
"S \NAC"
BN"41"15;
%"TAP"
"6","(-5575,3625)","0","mstr_standard","I64";
;
CDS_LIB"mstr_standard"
BODY_TYPE"PLUMBING"
HDL_TAP"TRUE";
"B \NAC \NWC"9;
"S \NAC"
BN"42"75;
%"TAP"
"6","(-5575,3675)","0","mstr_standard","I65";
;
CDS_LIB"mstr_standard"
BODY_TYPE"PLUMBING"
HDL_TAP"TRUE";
"B \NAC \NWC"9;
"S \NAC"
BN"43"76;
%"TAP"
"6","(-5575,3725)","0","mstr_standard","I66";
;
CDS_LIB"mstr_standard"
BODY_TYPE"PLUMBING"
HDL_TAP"TRUE";
"B \NAC \NWC"9;
"S \NAC"
BN"44"77;
%"TAP"
"6","(-5575,3775)","0","mstr_standard","I67";
;
CDS_LIB"mstr_standard"
BODY_TYPE"PLUMBING"
HDL_TAP"TRUE";
"B \NAC \NWC"9;
"S \NAC"
BN"45"78;
%"TAP"
"6","(-5575,3825)","0","mstr_standard","I68";
;
CDS_LIB"mstr_standard"
BODY_TYPE"PLUMBING"
HDL_TAP"TRUE";
"B \NAC \NWC"9;
"S \NAC"
BN"46"79;
%"TAP"
"6","(-5575,3875)","0","mstr_standard","I69";
;
CDS_LIB"mstr_standard"
BODY_TYPE"PLUMBING"
HDL_TAP"TRUE";
"B \NAC \NWC"9;
"S \NAC"
BN"47"80;
%"TAP"
"6","(-5575,775)","0","mstr_standard","I7";
;
CDS_LIB"mstr_standard"
BODY_TYPE"PLUMBING"
HDL_TAP"TRUE";
"B \NAC \NWC"10;
"S \NAC"
BN"3"47;
%"TAP"
"6","(-5575,3925)","0","mstr_standard","I70";
;
CDS_LIB"mstr_standard"
BODY_TYPE"PLUMBING"
HDL_TAP"TRUE";
"B \NAC \NWC"9;
"S \NAC"
BN"48"81;
%"TAP"
"6","(-5575,3975)","0","mstr_standard","I71";
;
CDS_LIB"mstr_standard"
BODY_TYPE"PLUMBING"
HDL_TAP"TRUE";
"B \NAC \NWC"9;
"S \NAC"
BN"49"82;
%"TAP"
"6","(-5575,4025)","0","mstr_standard","I73";
;
CDS_LIB"mstr_standard"
BODY_TYPE"PLUMBING"
HDL_TAP"TRUE";
"B \NAC \NWC"9;
"S \NAC"
BN"50"83;
%"TAP"
"6","(-5575,4075)","0","mstr_standard","I74";
;
CDS_LIB"mstr_standard"
BODY_TYPE"PLUMBING"
HDL_TAP"TRUE";
"B \NAC \NWC"9;
"S \NAC"
BN"51"84;
%"TAP"
"6","(-5575,4125)","0","mstr_standard","I75";
;
CDS_LIB"mstr_standard"
BODY_TYPE"PLUMBING"
HDL_TAP"TRUE";
"B \NAC \NWC"9;
"S \NAC"
BN"52"17;
%"TAP"
"6","(-5575,4175)","0","mstr_standard","I76";
;
CDS_LIB"mstr_standard"
BODY_TYPE"PLUMBING"
HDL_TAP"TRUE";
"B \NAC \NWC"9;
"S \NAC"
BN"53"85;
%"TAP"
"6","(-5575,4225)","0","mstr_standard","I77";
;
CDS_LIB"mstr_standard"
BODY_TYPE"PLUMBING"
HDL_TAP"TRUE";
"B \NAC \NWC"9;
"S \NAC"
BN"54"86;
%"TAP"
"6","(-5575,4275)","0","mstr_standard","I78";
;
CDS_LIB"mstr_standard"
BODY_TYPE"PLUMBING"
HDL_TAP"TRUE";
"B \NAC \NWC"9;
"S \NAC"
BN"55"13;
%"TAP"
"6","(-5575,4325)","0","mstr_standard","I79";
;
CDS_LIB"mstr_standard"
BODY_TYPE"PLUMBING"
HDL_TAP"TRUE";
"B \NAC \NWC"9;
"S \NAC"
BN"56"87;
%"TAP"
"6","(-5575,725)","0","mstr_standard","I8";
;
CDS_LIB"mstr_standard"
BODY_TYPE"PLUMBING"
HDL_TAP"TRUE";
"B \NAC \NWC"10;
"S \NAC"
BN"2"46;
%"TAP"
"6","(-5575,4375)","0","mstr_standard","I80";
;
CDS_LIB"mstr_standard"
BODY_TYPE"PLUMBING"
HDL_TAP"TRUE";
"B \NAC \NWC"9;
"S \NAC"
BN"57"88;
%"TAP"
"6","(-5575,4425)","0","mstr_standard","I81";
;
CDS_LIB"mstr_standard"
BODY_TYPE"PLUMBING"
HDL_TAP"TRUE";
"B \NAC \NWC"9;
"S \NAC"
BN"58"89;
%"TAP"
"6","(-5575,4475)","0","mstr_standard","I82";
;
CDS_LIB"mstr_standard"
BODY_TYPE"PLUMBING"
HDL_TAP"TRUE";
"B \NAC \NWC"9;
"S \NAC"
BN"59"90;
%"TAP"
"6","(-5575,4525)","0","mstr_standard","I83";
;
CDS_LIB"mstr_standard"
BODY_TYPE"PLUMBING"
HDL_TAP"TRUE";
"B \NAC \NWC"9;
"S \NAC"
BN"60"91;
%"TAP"
"6","(-5575,4575)","0","mstr_standard","I84";
;
CDS_LIB"mstr_standard"
BODY_TYPE"PLUMBING"
HDL_TAP"TRUE";
"B \NAC \NWC"9;
"S \NAC"
BN"61"92;
%"TAP"
"6","(-5575,4625)","0","mstr_standard","I85";
;
CDS_LIB"mstr_standard"
BODY_TYPE"PLUMBING"
HDL_TAP"TRUE";
"B \NAC \NWC"9;
"S \NAC"
BN"62"93;
%"TAP"
"6","(-5575,4675)","0","mstr_standard","I86";
;
CDS_LIB"mstr_standard"
BODY_TYPE"PLUMBING"
HDL_TAP"TRUE";
"B \NAC \NWC"9;
"S \NAC"
BN"63"94;
%"TAP"
"6","(-2850,775)","2","mstr_standard","I87";
;
CDS_LIB"mstr_standard"
BODY_TYPE"PLUMBING"
HDL_TAP"TRUE";
"B \NAC \NWC"4;
"S \NAC"
BN"1"116;
%"TAP"
"6","(-2850,725)","2","mstr_standard","I88";
;
CDS_LIB"mstr_standard"
BODY_TYPE"PLUMBING"
HDL_TAP"TRUE";
"B \NAC \NWC"4;
"S \NAC"
BN"0"115;
%"TAP"
"6","(-2850,825)","2","mstr_standard","I89";
;
CDS_LIB"mstr_standard"
BODY_TYPE"PLUMBING"
HDL_TAP"TRUE";
"B \NAC \NWC"5;
"S \NAC"
BN"0"113;
%"TAP"
"6","(-5575,875)","0","mstr_standard","I9";
;
CDS_LIB"mstr_standard"
BODY_TYPE"PLUMBING"
HDL_TAP"TRUE";
"B \NAC \NWC"11;
"S \NAC"
BN"1"41;
%"TAP"
"6","(-2850,875)","2","mstr_standard","I90";
;
CDS_LIB"mstr_standard"
BODY_TYPE"PLUMBING"
HDL_TAP"TRUE";
"B \NAC \NWC"5;
"S \NAC"
BN"1"114;
%"TAP"
"6","(-2850,1075)","2","mstr_standard","I91";
;
CDS_LIB"mstr_standard"
BODY_TYPE"PLUMBING"
HDL_TAP"TRUE";
"B \NAC \NWC"7;
"S \NAC"
BN"2"103;
%"TAP"
"6","(-2850,1025)","2","mstr_standard","I92";
;
CDS_LIB"mstr_standard"
BODY_TYPE"PLUMBING"
HDL_TAP"TRUE";
"B \NAC \NWC"7;
"S \NAC"
BN"1"102;
%"TAP"
"6","(-2850,975)","2","mstr_standard","I93";
;
CDS_LIB"mstr_standard"
BODY_TYPE"PLUMBING"
HDL_TAP"TRUE";
"B \NAC \NWC"7;
"S \NAC"
BN"0"101;
%"TAP"
"6","(-2850,1175)","2","mstr_standard","I94";
;
CDS_LIB"mstr_standard"
BODY_TYPE"PLUMBING"
HDL_TAP"TRUE";
"B \NAC \NWC"7;
"S \NAC"
BN"4"105;
%"TAP"
"6","(-2850,1125)","2","mstr_standard","I95";
;
CDS_LIB"mstr_standard"
BODY_TYPE"PLUMBING"
HDL_TAP"TRUE";
"B \NAC \NWC"7;
"S \NAC"
BN"3"104;
%"TAP"
"6","(-2850,1225)","2","mstr_standard","I96";
;
CDS_LIB"mstr_standard"
BODY_TYPE"PLUMBING"
HDL_TAP"TRUE";
"B \NAC \NWC"7;
"S \NAC"
BN"5"106;
%"TAP"
"6","(-2850,1275)","2","mstr_standard","I97";
;
CDS_LIB"mstr_standard"
BODY_TYPE"PLUMBING"
HDL_TAP"TRUE";
"B \NAC \NWC"7;
"S \NAC"
BN"6"107;
%"TAP"
"6","(-2850,1325)","2","mstr_standard","I98";
;
CDS_LIB"mstr_standard"
BODY_TYPE"PLUMBING"
HDL_TAP"TRUE";
"B \NAC \NWC"7;
"S \NAC"
BN"7"108;
%"TAP"
"6","(-2850,1425)","2","mstr_standard","I99";
;
CDS_LIB"mstr_standard"
BODY_TYPE"PLUMBING"
HDL_TAP"TRUE";
"B \NAC \NWC"8;
"S \NAC"
BN"0"95;
END.
